# T6G (Grand Teton) — schematic netlist excerpt (pin names and nets, part order shuffled) for the footprints in the layout excerpt that follows; sources: Cadence DE-HDL packaged netlist, KiCad conversion of 04192023_DAF0TMB3IC0_F0TG_MB_C_brd_V02_OCP.brd

PR3828  Q_RES  15K 1% CHIP  pkg 0402LF  page 140 : A = P12V_OCP_OV_2 ; B = GND

(kicad_pcb
	(version 20260206)
	(generator "pcbnew")
	(generator_version "10.0")
	(general
		(thickness 1.6)
		(legacy_teardrops no)
	)
	(paper "A4")
	(title_block
		(title "04192023_DAF0TMB3IC0_F0TG_MB_C_brd_V02_OCP.brd")
		(comment 1 "Grand Teton / footprints 231-231 of 8354")
	)
	(layers
		(0 "F.Cu" signal "TOP")
		(4 "In1.Cu" signal "GND")
		(6 "In2.Cu" signal "IN1")
		(8 "In3.Cu" signal "GND1")
		(10 "In4.Cu" signal "IN2")
		(12 "In5.Cu" signal "GND2")
		(14 "In6.Cu" signal "IN3")
		(16 "In7.Cu" signal "GND3")
		(18 "In8.Cu" signal "VCC")
		(20 "In9.Cu" signal "VCC1")
		(22 "In10.Cu" signal "GND4")
		(24 "In11.Cu" signal "IN4")
		(26 "In12.Cu" signal "GND5")
		(28 "In13.Cu" signal "IN5")
		(30 "In14.Cu" signal "GND6")
		(32 "In15.Cu" signal "IN6")
		(34 "In16.Cu" signal "GND7")
		(2 "B.Cu" signal "BOTTOM")
		(9 "F.Adhes" user "F.Adhesive")
		(11 "B.Adhes" user "B.Adhesive")
		(13 "F.Paste" user "Package Geometry/Pastemask Top")
		(15 "B.Paste" user "Package Geometry/Pastemask Bottom")
		(5 "F.SilkS" user "Ref Des/Silkscreen Top")
		(7 "B.SilkS" user "Ref Des/Silkscreen Bottom")
		(1 "F.Mask" user "Board Geometry/Soldermask Top")
		(3 "B.Mask" user "Board Geometry/Soldermask Bottom")
		(17 "Dwgs.User" user "User.Drawings")
		(19 "Cmts.User" user "User.Comments")
		(21 "Eco1.User" user "User.Eco1")
		(23 "Eco2.User" user "User.Eco2")
		(25 "Edge.Cuts" user "Board Geometry/Outline")
		(27 "Margin" user)
		(31 "F.CrtYd" user "Package Geometry/Place Bound Top")
		(29 "B.CrtYd" user "Package Geometry/Place Bound Bottom")
		(35 "F.Fab" user "Ref Des/Assembly Top")
		(33 "B.Fab" user "Ref Des/Assembly Bottom")
	)
	(footprint ""
		(layer "F.Cu")
		(at 76.115164 -17.050512 180)
		(property "Reference" "PR3828"
			(at 0 0 180)
			(layer "F.SilkS")
			(hide yes)
			(effects
				(font
					(size 1.27 1.27)
				)
			)
		)
		(property "Value" ""
			(at 0 0 180)
			(layer "F.Fab")
			(effects
				(font
					(size 1.27 1.27)
				)
			)
		)
		(duplicate_pad_numbers_are_jumpers no)
		(fp_line
			(start 0.7874 0.4064)
			(end -0.7874 0.4064)
			(stroke
				(width 0.1524)
				(type default)
			)
			(layer "F.SilkS")
		)
		(fp_line
			(start 0.7874 -0.4064)
			(end 0.7874 0.4064)
			(stroke
				(width 0.1524)
				(type default)
			)
			(layer "F.SilkS")
		)
		(fp_line
			(start -0.7874 0.4064)
			(end -0.7874 -0.4064)
			(stroke
				(width 0.1524)
				(type default)
			)
			(layer "F.SilkS")
		)
		(fp_line
			(start -0.7874 -0.4064)
			(end 0.7874 -0.4064)
			(stroke
				(width 0.1524)
				(type default)
			)
			(layer "F.SilkS")
		)
		(fp_line
			(start 0.67945 0.3048)
			(end 0.120396 0.3048)
			(stroke
				(width 0.1)
				(type default)
			)
			(layer "F.Fab")
		)
		(fp_line
			(start 0.67945 -0.3048)
			(end 0.67945 0.3048)
			(stroke
				(width 0.1)
				(type default)
			)
			(layer "F.Fab")
		)
		(fp_line
			(start 0.12065 -0.2794)
			(end 0.12065 -0.3048)
			(stroke
				(width 0.1)
				(type default)
			)
			(layer "F.Fab")
		)
		(fp_line
			(start 0.12065 -0.3048)
			(end 0.67945 -0.3048)
			(stroke
				(width 0.1)
				(type default)
			)
			(layer "F.Fab")
		)
		(fp_line
			(start 0.120396 0.3048)
			(end 0.120396 0.2794)
			(stroke
				(width 0.1)
				(type default)
			)
			(layer "F.Fab")
		)
		(fp_line
			(start 0.120396 0.2794)
			(end -0.12065 0.2794)
			(stroke
				(width 0.1)
				(type default)
			)
			(layer "F.Fab")
		)
		(fp_line
			(start -0.12065 0.3048)
			(end -0.67945 0.3048)
			(stroke
				(width 0.1)
				(type default)
			)
			(layer "F.Fab")
		)
		(fp_line
			(start -0.12065 0.2794)
			(end -0.12065 0.3048)
			(stroke
				(width 0.1)
				(type default)
			)
			(layer "F.Fab")
		)
		(fp_line
			(start -0.12065 -0.2794)
			(end 0.12065 -0.2794)
			(stroke
				(width 0.1)
				(type default)
			)
			(layer "F.Fab")
		)
		(fp_line
			(start -0.12065 -0.305054)
			(end -0.12065 -0.2794)
			(stroke
				(width 0.1)
				(type default)
			)
			(layer "F.Fab")
		)
		(fp_line
			(start -0.67945 0.3048)
			(end -0.67945 -0.305054)
			(stroke
				(width 0.1)
				(type default)
			)
			(layer "F.Fab")
		)
		(fp_line
			(start -0.67945 -0.305054)
			(end -0.12065 -0.305054)
			(stroke
				(width 0.1)
				(type default)
			)
			(layer "F.Fab")
		)
		(pad "1" smd circle
			(at -0.40005 0 180)
			(size 0 0)
			(layers "F.Cu" "F.Mask" "F.Paste")
			(net "P12V_OCP_OV_2")
		)
		(pad "2" smd circle
			(at 0.40005 0 180)
			(size 0 0)
			(layers "F.Cu" "F.Mask" "F.Paste")
			(net "GND")
		)
	)
)
